(kicad_pcb
	(version 20260206)
	(generator "pcbnew")
	(generator_version "10.0")
	(general
		(thickness 1.6)
		(legacy_teardrops no)
	)
	(paper "A4")
	(title_block
		(title "12092022_DA0F0TMDCD0_F0T_Management_Board_D_brd_V3_OCP.brd")
		(comment 1 "Grand Teton / footprints 515-520 of 1440")
	)
	(layers
		(0 "F.Cu" signal "TOP")
		(4 "In1.Cu" signal "GND")
		(6 "In2.Cu" signal "IN1")
		(8 "In3.Cu" signal "GND1")
		(10 "In4.Cu" signal "IN2")
		(12 "In5.Cu" signal "VCC")
		(14 "In6.Cu" signal "VCC1")
		(16 "In7.Cu" signal "IN3")
		(18 "In8.Cu" signal "GND2")
		(20 "In9.Cu" signal "IN4")
		(22 "In10.Cu" signal "GND3")
		(2 "B.Cu" signal "BOTTOM")
		(9 "F.Adhes" user "F.Adhesive")
		(11 "B.Adhes" user "B.Adhesive")
		(13 "F.Paste" user "Package Geometry/Pastemask Top")
		(15 "B.Paste" user "Package Geometry/Pastemask Bottom")
		(5 "F.SilkS" user "Ref Des/Silkscreen Top")
		(7 "B.SilkS" user "Ref Des/Silkscreen Bottom")
		(1 "F.Mask" user "Board Geometry/Soldermask Top")
		(3 "B.Mask" user "Board Geometry/Soldermask Bottom")
		(17 "Dwgs.User" user "User.Drawings")
		(19 "Cmts.User" user "User.Comments")
		(21 "Eco1.User" user "User.Eco1")
		(23 "Eco2.User" user "User.Eco2")
		(25 "Edge.Cuts" user "Board Geometry/Outline")
		(27 "Margin" user)
		(31 "F.CrtYd" user "Package Geometry/Place Bound Top")
		(29 "B.CrtYd" user "Package Geometry/Place Bound Bottom")
		(35 "F.Fab" user "Ref Des/Assembly Top")
		(33 "B.Fab" user "Ref Des/Assembly Bottom")
	)
	(footprint ""
		(layer "F.Cu")
		(at 10.767568 -50.110898 -90)
		(property "Reference" "PR526"
			(at 0 0 270)
			(layer "F.SilkS")
			(hide yes)
			(effects
				(font
					(size 1.27 1.27)
				)
			)
		)
		(property "Value" ""
			(at 0 0 270)
			(layer "F.Fab")
			(effects
				(font
					(size 1.27 1.27)
				)
			)
		)
		(duplicate_pad_numbers_are_jumpers no)
		(fp_line
			(start -0.7874 0.4064)
			(end -0.7874 -0.4064)
			(stroke
				(width 0.1524)
				(type default)
			)
			(layer "F.SilkS")
		)
		(fp_line
			(start 0.7874 0.4064)
			(end -0.7874 0.4064)
			(stroke
				(width 0.1524)
				(type default)
			)
			(layer "F.SilkS")
		)
		(fp_line
			(start -0.7874 -0.4064)
			(end 0.7874 -0.4064)
			(stroke
				(width 0.1524)
				(type default)
			)
			(layer "F.SilkS")
		)
		(fp_line
			(start 0.7874 -0.4064)
			(end 0.7874 0.4064)
			(stroke
				(width 0.1524)
				(type default)
			)
			(layer "F.SilkS")
		)
		(fp_line
			(start -0.67945 0.3048)
			(end -0.67945 -0.305054)
			(stroke
				(width 0.1)
				(type default)
			)
			(layer "F.Fab")
		)
		(fp_line
			(start -0.12065 0.3048)
			(end -0.67945 0.3048)
			(stroke
				(width 0.1)
				(type default)
			)
			(layer "F.Fab")
		)
		(fp_line
			(start 0.120396 0.3048)
			(end 0.120396 0.2794)
			(stroke
				(width 0.1)
				(type default)
			)
			(layer "F.Fab")
		)
		(fp_line
			(start 0.67945 0.3048)
			(end 0.120396 0.3048)
			(stroke
				(width 0.1)
				(type default)
			)
			(layer "F.Fab")
		)
		(fp_line
			(start -0.12065 0.2794)
			(end -0.12065 0.3048)
			(stroke
				(width 0.1)
				(type default)
			)
			(layer "F.Fab")
		)
		(fp_line
			(start 0.120396 0.2794)
			(end -0.12065 0.2794)
			(stroke
				(width 0.1)
				(type default)
			)
			(layer "F.Fab")
		)
		(fp_line
			(start -0.12065 -0.2794)
			(end 0.12065 -0.2794)
			(stroke
				(width 0.1)
				(type default)
			)
			(layer "F.Fab")
		)
		(fp_line
			(start 0.12065 -0.2794)
			(end 0.12065 -0.3048)
			(stroke
				(width 0.1)
				(type default)
			)
			(layer "F.Fab")
		)
		(fp_line
			(start 0.12065 -0.3048)
			(end 0.67945 -0.3048)
			(stroke
				(width 0.1)
				(type default)
			)
			(layer "F.Fab")
		)
		(fp_line
			(start 0.67945 -0.3048)
			(end 0.67945 0.3048)
			(stroke
				(width 0.1)
				(type default)
			)
			(layer "F.Fab")
		)
		(fp_line
			(start -0.67945 -0.305054)
			(end -0.12065 -0.305054)
			(stroke
				(width 0.1)
				(type default)
			)
			(layer "F.Fab")
		)
		(fp_line
			(start -0.12065 -0.305054)
			(end -0.12065 -0.2794)
			(stroke
				(width 0.1)
				(type default)
			)
			(layer "F.Fab")
		)
		(pad "1" smd circle
			(at -0.40005 0 270)
			(size 0 0)
			(layers "F.Cu" "F.Mask" "F.Paste")
			(net "P5V_AUX_FB")
		)
		(pad "2" smd circle
			(at 0.40005 0 270)
			(size 0 0)
			(layers "F.Cu" "F.Mask" "F.Paste")
			(net "GND")
		)
	)
	(footprint ""
		(layer "F.Cu")
		(at 49.2125 -98.298 90)
		(property "Reference" "R287"
			(at 0 0 90)
			(layer "F.SilkS")
			(hide yes)
			(effects
				(font
					(size 1.27 1.27)
				)
			)
		)
		(property "Value" ""
			(at 0 0 90)
			(layer "F.Fab")
			(effects
				(font
					(size 1.27 1.27)
				)
			)
		)
		(duplicate_pad_numbers_are_jumpers no)
		(fp_line
			(start 0.7874 -0.4064)
			(end 0.7874 0.4064)
			(stroke
				(width 0.1524)
				(type default)
			)
			(layer "F.SilkS")
		)
		(fp_line
			(start -0.7874 -0.4064)
			(end 0.7874 -0.4064)
			(stroke
				(width 0.1524)
				(type default)
			)
			(layer "F.SilkS")
		)
		(fp_line
			(start 0.7874 0.4064)
			(end -0.7874 0.4064)
			(stroke
				(width 0.1524)
				(type default)
			)
			(layer "F.SilkS")
		)
		(fp_line
			(start -0.7874 0.4064)
			(end -0.7874 -0.4064)
			(stroke
				(width 0.1524)
				(type default)
			)
			(layer "F.SilkS")
		)
		(fp_line
			(start -0.12065 -0.305054)
			(end -0.12065 -0.2794)
			(stroke
				(width 0.1)
				(type default)
			)
			(layer "F.Fab")
		)
		(fp_line
			(start -0.67945 -0.305054)
			(end -0.12065 -0.305054)
			(stroke
				(width 0.1)
				(type default)
			)
			(layer "F.Fab")
		)
		(fp_line
			(start 0.67945 -0.3048)
			(end 0.67945 0.3048)
			(stroke
				(width 0.1)
				(type default)
			)
			(layer "F.Fab")
		)
		(fp_line
			(start 0.12065 -0.3048)
			(end 0.67945 -0.3048)
			(stroke
				(width 0.1)
				(type default)
			)
			(layer "F.Fab")
		)
		(fp_line
			(start 0.12065 -0.2794)
			(end 0.12065 -0.3048)
			(stroke
				(width 0.1)
				(type default)
			)
			(layer "F.Fab")
		)
		(fp_line
			(start -0.12065 -0.2794)
			(end 0.12065 -0.2794)
			(stroke
				(width 0.1)
				(type default)
			)
			(layer "F.Fab")
		)
		(fp_line
			(start 0.120396 0.2794)
			(end -0.12065 0.2794)
			(stroke
				(width 0.1)
				(type default)
			)
			(layer "F.Fab")
		)
		(fp_line
			(start -0.12065 0.2794)
			(end -0.12065 0.3048)
			(stroke
				(width 0.1)
				(type default)
			)
			(layer "F.Fab")
		)
		(fp_line
			(start 0.67945 0.3048)
			(end 0.120396 0.3048)
			(stroke
				(width 0.1)
				(type default)
			)
			(layer "F.Fab")
		)
		(fp_line
			(start 0.120396 0.3048)
			(end 0.120396 0.2794)
			(stroke
				(width 0.1)
				(type default)
			)
			(layer "F.Fab")
		)
		(fp_line
			(start -0.12065 0.3048)
			(end -0.67945 0.3048)
			(stroke
				(width 0.1)
				(type default)
			)
			(layer "F.Fab")
		)
		(fp_line
			(start -0.67945 0.3048)
			(end -0.67945 -0.305054)
			(stroke
				(width 0.1)
				(type default)
			)
			(layer "F.Fab")
		)
		(pad "1" smd circle
			(at -0.40005 0 90)
			(size 0 0)
			(layers "F.Cu" "F.Mask" "F.Paste")
			(net "P3V3_RGM")
		)
		(pad "2" smd circle
			(at 0.40005 0 90)
			(size 0 0)
			(layers "F.Cu" "F.Mask" "F.Paste")
			(net "RST_BMC_EXTRST_R2_N")
		)
	)
	(footprint ""
		(layer "F.Cu")
		(at 21.971 -66.1162 90)
		(property "Reference" "C500"
			(at 0 0 90)
			(layer "F.SilkS")
			(hide yes)
			(effects
				(font
					(size 1.27 1.27)
				)
			)
		)
		(property "Value" ""
			(at 0 0 90)
			(layer "F.Fab")
			(effects
				(font
					(size 1.27 1.27)
				)
			)
		)
		(duplicate_pad_numbers_are_jumpers no)
		(fp_line
			(start 0.7874 -0.4064)
			(end 0.7874 0.4064)
			(stroke
				(width 0.1524)
				(type default)
			)
			(layer "F.SilkS")
		)
		(fp_line
			(start -0.7874 -0.4064)
			(end 0.7874 -0.4064)
			(stroke
				(width 0.1524)
				(type default)
			)
			(layer "F.SilkS")
		)
		(fp_line
			(start 0.7874 0.4064)
			(end -0.7874 0.4064)
			(stroke
				(width 0.1524)
				(type default)
			)
			(layer "F.SilkS")
		)
		(fp_line
			(start -0.7874 0.4064)
			(end -0.7874 -0.4064)
			(stroke
				(width 0.1524)
				(type default)
			)
			(layer "F.SilkS")
		)
		(fp_line
			(start -0.12065 -0.305054)
			(end -0.12065 -0.2794)
			(stroke
				(width 0.1)
				(type default)
			)
			(layer "F.Fab")
		)
		(fp_line
			(start -0.67945 -0.305054)
			(end -0.12065 -0.305054)
			(stroke
				(width 0.1)
				(type default)
			)
			(layer "F.Fab")
		)
		(fp_line
			(start 0.67945 -0.3048)
			(end 0.67945 0.3048)
			(stroke
				(width 0.1)
				(type default)
			)
			(layer "F.Fab")
		)
		(fp_line
			(start 0.12065 -0.3048)
			(end 0.67945 -0.3048)
			(stroke
				(width 0.1)
				(type default)
			)
			(layer "F.Fab")
		)
		(fp_line
			(start 0.12065 -0.2794)
			(end 0.12065 -0.3048)
			(stroke
				(width 0.1)
				(type default)
			)
			(layer "F.Fab")
		)
		(fp_line
			(start -0.12065 -0.2794)
			(end 0.12065 -0.2794)
			(stroke
				(width 0.1)
				(type default)
			)
			(layer "F.Fab")
		)
		(fp_line
			(start 0.120396 0.2794)
			(end -0.12065 0.2794)
			(stroke
				(width 0.1)
				(type default)
			)
			(layer "F.Fab")
		)
		(fp_line
			(start -0.12065 0.2794)
			(end -0.12065 0.3048)
			(stroke
				(width 0.1)
				(type default)
			)
			(layer "F.Fab")
		)
		(fp_line
			(start 0.67945 0.3048)
			(end 0.120396 0.3048)
			(stroke
				(width 0.1)
				(type default)
			)
			(layer "F.Fab")
		)
		(fp_line
			(start 0.120396 0.3048)
			(end 0.120396 0.2794)
			(stroke
				(width 0.1)
				(type default)
			)
			(layer "F.Fab")
		)
		(fp_line
			(start -0.12065 0.3048)
			(end -0.67945 0.3048)
			(stroke
				(width 0.1)
				(type default)
			)
			(layer "F.Fab")
		)
		(fp_line
			(start -0.67945 0.3048)
			(end -0.67945 -0.305054)
			(stroke
				(width 0.1)
				(type default)
			)
			(layer "F.Fab")
		)
		(pad "1" smd circle
			(at -0.40005 0 90)
			(size 0 0)
			(layers "F.Cu" "F.Mask" "F.Paste")
			(net "P3V3_AUX")
		)
		(pad "2" smd circle
			(at 0.40005 0 90)
			(size 0 0)
			(layers "F.Cu" "F.Mask" "F.Paste")
			(net "GND")
		)
	)
	(footprint ""
		(layer "F.Cu")
		(at 61.469016 -81.10474)
		(property "Reference" "R508"
			(at 0 0 0)
			(layer "F.SilkS")
			(hide yes)
			(effects
				(font
					(size 1.27 1.27)
				)
			)
		)
		(property "Value" ""
			(at 0 0 0)
			(layer "F.Fab")
			(effects
				(font
					(size 1.27 1.27)
				)
			)
		)
		(duplicate_pad_numbers_are_jumpers no)
		(fp_line
			(start -0.7874 -0.4064)
			(end 0.7874 -0.4064)
			(stroke
				(width 0.1524)
				(type default)
			)
			(layer "F.SilkS")
		)
		(fp_line
			(start -0.7874 0.4064)
			(end -0.7874 -0.4064)
			(stroke
				(width 0.1524)
				(type default)
			)
			(layer "F.SilkS")
		)
		(fp_line
			(start 0.7874 -0.4064)
			(end 0.7874 0.4064)
			(stroke
				(width 0.1524)
				(type default)
			)
			(layer "F.SilkS")
		)
		(fp_line
			(start 0.7874 0.4064)
			(end -0.7874 0.4064)
			(stroke
				(width 0.1524)
				(type default)
			)
			(layer "F.SilkS")
		)
		(fp_line
			(start -0.67945 -0.305054)
			(end -0.12065 -0.305054)
			(stroke
				(width 0.1)
				(type default)
			)
			(layer "F.Fab")
		)
		(fp_line
			(start -0.67945 0.3048)
			(end -0.67945 -0.305054)
			(stroke
				(width 0.1)
				(type default)
			)
			(layer "F.Fab")
		)
		(fp_line
			(start -0.12065 -0.305054)
			(end -0.12065 -0.2794)
			(stroke
				(width 0.1)
				(type default)
			)
			(layer "F.Fab")
		)
		(fp_line
			(start -0.12065 -0.2794)
			(end 0.12065 -0.2794)
			(stroke
				(width 0.1)
				(type default)
			)
			(layer "F.Fab")
		)
		(fp_line
			(start -0.12065 0.2794)
			(end -0.12065 0.3048)
			(stroke
				(width 0.1)
				(type default)
			)
			(layer "F.Fab")
		)
		(fp_line
			(start -0.12065 0.3048)
			(end -0.67945 0.3048)
			(stroke
				(width 0.1)
				(type default)
			)
			(layer "F.Fab")
		)
		(fp_line
			(start 0.120396 0.2794)
			(end -0.12065 0.2794)
			(stroke
				(width 0.1)
				(type default)
			)
			(layer "F.Fab")
		)
		(fp_line
			(start 0.120396 0.3048)
			(end 0.120396 0.2794)
			(stroke
				(width 0.1)
				(type default)
			)
			(layer "F.Fab")
		)
		(fp_line
			(start 0.12065 -0.3048)
			(end 0.67945 -0.3048)
			(stroke
				(width 0.1)
				(type default)
			)
			(layer "F.Fab")
		)
		(fp_line
			(start 0.12065 -0.2794)
			(end 0.12065 -0.3048)
			(stroke
				(width 0.1)
				(type default)
			)
			(layer "F.Fab")
		)
		(fp_line
			(start 0.67945 -0.3048)
			(end 0.67945 0.3048)
			(stroke
				(width 0.1)
				(type default)
			)
			(layer "F.Fab")
		)
		(fp_line
			(start 0.67945 0.3048)
			(end 0.120396 0.3048)
			(stroke
				(width 0.1)
				(type default)
			)
			(layer "F.Fab")
		)
		(pad "1" smd circle
			(at -0.40005 0)
			(size 0 0)
			(layers "F.Cu" "F.Mask" "F.Paste")
			(net "P3V3_AUX")
		)
		(pad "2" smd circle
			(at 0.40005 0)
			(size 0 0)
			(layers "F.Cu" "F.Mask" "F.Paste")
			(net "MB_JTAG_PLD_R_JTAGEN")
		)
	)
	(footprint ""
		(layer "F.Cu")
		(at 86.522306 -109.933486 90)
		(property "Reference" "H2B1"
			(at -3.102356 -3.769106 0)
			(unlocked yes)
			(layer "F.SilkS")
			(effects
				(font
					(size 0.7874 0.5842)
					(thickness 0.1524)
				)
				(justify left)
			)
		)
		(property "Value" ""
			(at 0 0 90)
			(layer "F.Fab")
			(effects
				(font
					(size 1.27 1.27)
				)
			)
		)
		(duplicate_pad_numbers_are_jumpers no)
		(fp_circle
			(center 0 0)
			(end 0 2.4003)
			(stroke
				(width 0.1524)
				(type default)
			)
			(fill no)
			(layer "F.SilkS")
		)
		(fp_arc
			(start -6.015482 2.690876)
			(mid -2.409198 -6.133258)
			(end 6.23951 -2.124456)
			(stroke
				(width 0.1524)
				(type default)
			)
			(layer "B.SilkS")
		)
		(fp_circle
			(center 0 0)
			(end 0 6.5913)
			(stroke
				(width 0.1)
				(type default)
			)
			(fill no)
			(layer "B.Fab")
		)
		(fp_circle
			(center 0 0)
			(end 0 2.4003)
			(stroke
				(width 0.1)
				(type default)
			)
			(fill no)
			(layer "F.Fab")
		)
		(pad "" np_thru_hole circle
			(at 0 0 90)
			(size 3.175 3.175)
			(drill 3.175)
			(layers "*.Cu" "*.Mask")
			(clearance 0.381)
			(thermal_gap 0.381)
		)
		(zone
			(layers "F.Cu" "B.Cu" "In1.Cu" "In2.Cu" "In3.Cu" "In4.Cu" "In5.Cu" "In6.Cu"
				"In7.Cu" "In8.Cu" "In9.Cu" "In10.Cu"
			)
			(hatch none 0.5)
			(connect_pads
				(clearance 0)
			)
			(min_thickness 0.25)
			(keepout
				(tracks not_allowed)
				(vias allowed)
				(pads allowed)
				(copperpour not_allowed)
				(footprints allowed)
			)
			(placement
				(enabled no)
				(sheetname "")
			)
			(fill
				(thermal_gap 0.5)
				(thermal_bridge_width 0.5)
				(island_removal_mode 0)
			)
			(polygon
				(pts
					(arc
						(start 88.617806 -109.933486)
						(mid 84.426806 -109.933486)
						(end 88.617806 -109.933486)
					)
				)
			)
		)
	)
	(footprint ""
		(layer "F.Cu")
		(at 40.556942 -22.15642 -90)
		(property "Reference" "R673"
			(at 0 0 270)
			(layer "F.SilkS")
			(hide yes)
			(effects
				(font
					(size 1.27 1.27)
				)
			)
		)
		(property "Value" ""
			(at 0 0 270)
			(layer "F.Fab")
			(effects
				(font
					(size 1.27 1.27)
				)
			)
		)
		(duplicate_pad_numbers_are_jumpers no)
		(fp_line
			(start 0.7874 0.4064)
			(end -0.7874 0.4064)
			(stroke
				(width 0.1524)
				(type default)
			)
			(layer "F.SilkS")
		)
		(fp_line
			(start -0.7874 -0.4064)
			(end 0.7874 -0.4064)
			(stroke
				(width 0.1524)
				(type default)
			)
			(layer "F.SilkS")
		)
		(fp_line
			(start -0.67945 0.3048)
			(end -0.67945 -0.305054)
			(stroke
				(width 0.1)
				(type default)
			)
			(layer "F.Fab")
		)
		(fp_line
			(start -0.12065 0.3048)
			(end -0.67945 0.3048)
			(stroke
				(width 0.1)
				(type default)
			)
			(layer "F.Fab")
		)
		(fp_line
			(start 0.120396 0.3048)
			(end 0.120396 0.2794)
			(stroke
				(width 0.1)
				(type default)
			)
			(layer "F.Fab")
		)
		(fp_line
			(start 0.67945 0.3048)
			(end 0.120396 0.3048)
			(stroke
				(width 0.1)
				(type default)
			)
			(layer "F.Fab")
		)
		(fp_line
			(start -0.12065 0.2794)
			(end -0.12065 0.3048)
			(stroke
				(width 0.1)
				(type default)
			)
			(layer "F.Fab")
		)
		(fp_line
			(start 0.120396 0.2794)
			(end -0.12065 0.2794)
			(stroke
				(width 0.1)
				(type default)
			)
			(layer "F.Fab")
		)
		(fp_line
			(start -0.12065 -0.2794)
			(end 0.12065 -0.2794)
			(stroke
				(width 0.1)
				(type default)
			)
			(layer "F.Fab")
		)
		(fp_line
			(start 0.12065 -0.2794)
			(end 0.12065 -0.3048)
			(stroke
				(width 0.1)
				(type default)
			)
			(layer "F.Fab")
		)
		(fp_line
			(start 0.12065 -0.3048)
			(end 0.67945 -0.3048)
			(stroke
				(width 0.1)
				(type default)
			)
			(layer "F.Fab")
		)
		(fp_line
			(start 0.67945 -0.3048)
			(end 0.67945 0.3048)
			(stroke
				(width 0.1)
				(type default)
			)
			(layer "F.Fab")
		)
		(fp_line
			(start -0.67945 -0.305054)
			(end -0.12065 -0.305054)
			(stroke
				(width 0.1)
				(type default)
			)
			(layer "F.Fab")
		)
		(fp_line
			(start -0.12065 -0.305054)
			(end -0.12065 -0.2794)
			(stroke
				(width 0.1)
				(type default)
			)
			(layer "F.Fab")
		)
		(pad "1" smd circle
			(at -0.40005 0 270)
			(size 0 0)
			(layers "F.Cu" "F.Mask" "F.Paste")
			(net "USB3_01_MUX_FB_TXP")
		)
		(pad "2" smd circle
			(at 0.40005 0 270)
			(size 0 0)
			(layers "F.Cu" "F.Mask" "F.Paste")
			(net "USB3_01_FB_TXP")
		)
	)
)
